(kicad_pcb
	(version 20260206)
	(generator "pcbnew")
	(generator_version "10.0")
	(general
		(thickness 1.6)
		(legacy_teardrops no)
	)
	(paper "A4")
	(title_block
		(title "dpb — 14545-sa.0730WZS0815.brd")
		(comment 1 "Honey Badger (Wiwynn) / footprints 181-183 of 1066")
	)
	(layers
		(0 "F.Cu" signal "TOP")
		(4 "In1.Cu" signal "L2GND")
		(6 "In2.Cu" signal "L3")
		(8 "In3.Cu" signal "L4VCC")
		(10 "In4.Cu" signal "L5VCC")
		(12 "In5.Cu" signal "L6")
		(14 "In6.Cu" signal "L7GND")
		(2 "B.Cu" signal "BOTTOM")
		(9 "F.Adhes" user "F.Adhesive")
		(11 "B.Adhes" user "B.Adhesive")
		(13 "F.Paste" user "Package Geometry/Pastemask Top")
		(15 "B.Paste" user "Package Geometry/Pastemask Bottom")
		(5 "F.SilkS" user "Ref Des/Silkscreen Top")
		(7 "B.SilkS" user "Ref Des/Silkscreen Bottom")
		(1 "F.Mask" user "Board Geometry/Soldermask Top")
		(3 "B.Mask" user "Board Geometry/Soldermask Bottom")
		(17 "Dwgs.User" user "User.Drawings")
		(19 "Cmts.User" user "User.Comments")
		(21 "Eco1.User" user "User.Eco1")
		(23 "Eco2.User" user "User.Eco2")
		(25 "Edge.Cuts" user "Board Geometry/Outline")
		(27 "Margin" user)
		(31 "F.CrtYd" user "Package Geometry/Place Bound Top")
		(29 "B.CrtYd" user "Package Geometry/Place Bound Bottom")
		(35 "F.Fab" user "Ref Des/Assembly Top")
		(33 "B.Fab" user "Ref Des/Assembly Bottom")
	)
	(footprint ""
		(layer "F.Cu")
		(at 42.500042 -67.669918 90)
		(property "Reference" "SKT10"
			(at 0 0 90)
			(layer "F.SilkS")
			(hide yes)
			(effects
				(font
					(size 1.27 1.27)
				)
			)
		)
		(property "Value" "SKT-SATA14P-15P-12-GP"
			(at -22.6187 8.1788 90)
			(unlocked yes)
			(layer "F.Fab")
			(hide yes)
			(effects
				(font
					(size 1.016 1.016)
					(thickness 0.1524)
				)
			)
		)
		(property "Device Type" "87945-1001"
			(at -22.6187 6.6548 90)
			(unlocked yes)
			(layer "F.Fab")
			(hide yes)
			(effects
				(font
					(size 1.016 1.016)
					(thickness 0.1524)
				)
			)
		)
		(duplicate_pad_numbers_are_jumpers no)
		(fp_line
			(start -15.3924 -5.8547)
			(end -16.3576 -5.8547)
			(stroke
				(width 0.3302)
				(type default)
			)
			(layer "F.SilkS")
		)
		(fp_line
			(start 20.4724 -5.7658)
			(end 20.4724 -2.3114)
			(stroke
				(width 0.1524)
				(type default)
			)
			(layer "F.SilkS")
		)
		(fp_line
			(start -20.4724 -5.7658)
			(end 20.4724 -5.7658)
			(stroke
				(width 0.1524)
				(type default)
			)
			(layer "F.SilkS")
		)
		(fp_line
			(start 23.7617 -2.3114)
			(end 23.7617 2.3114)
			(stroke
				(width 0.1524)
				(type default)
			)
			(layer "F.SilkS")
		)
		(fp_line
			(start 20.4724 -2.3114)
			(end 23.7617 -2.3114)
			(stroke
				(width 0.1524)
				(type default)
			)
			(layer "F.SilkS")
		)
		(fp_line
			(start -20.4724 -2.3114)
			(end -20.4724 -5.7658)
			(stroke
				(width 0.1524)
				(type default)
			)
			(layer "F.SilkS")
		)
		(fp_line
			(start -23.7617 -2.3114)
			(end -20.4724 -2.3114)
			(stroke
				(width 0.1524)
				(type default)
			)
			(layer "F.SilkS")
		)
		(fp_line
			(start 23.117556 -0.5461)
			(end 23.117556 0.5461)
			(stroke
				(width 0.3048)
				(type default)
			)
			(layer "F.SilkS")
		)
		(fp_line
			(start -20.882356 -0.5461)
			(end -20.882356 0.5461)
			(stroke
				(width 0.3048)
				(type default)
			)
			(layer "F.SilkS")
		)
		(fp_line
			(start 20.882356 0.5461)
			(end 20.882356 -0.5461)
			(stroke
				(width 0.3048)
				(type default)
			)
			(layer "F.SilkS")
		)
		(fp_line
			(start -23.117556 0.5461)
			(end -23.117556 -0.5461)
			(stroke
				(width 0.3048)
				(type default)
			)
			(layer "F.SilkS")
		)
		(fp_line
			(start 23.7617 2.3114)
			(end 20.4724 2.3114)
			(stroke
				(width 0.1524)
				(type default)
			)
			(layer "F.SilkS")
		)
		(fp_line
			(start 20.4724 2.3114)
			(end 20.4724 9.652)
			(stroke
				(width 0.1524)
				(type default)
			)
			(layer "F.SilkS")
		)
		(fp_line
			(start -20.4724 2.3114)
			(end -23.7617 2.3114)
			(stroke
				(width 0.1524)
				(type default)
			)
			(layer "F.SilkS")
		)
		(fp_line
			(start -23.7617 2.3114)
			(end -23.7617 -2.3114)
			(stroke
				(width 0.1524)
				(type default)
			)
			(layer "F.SilkS")
		)
		(fp_line
			(start 17.8435 7.9502)
			(end -17.8435 7.9502)
			(stroke
				(width 0.1524)
				(type default)
			)
			(layer "F.SilkS")
		)
		(fp_line
			(start -17.8435 7.9502)
			(end -17.8435 9.652)
			(stroke
				(width 0.1524)
				(type default)
			)
			(layer "F.SilkS")
		)
		(fp_line
			(start 20.4724 9.652)
			(end 17.8435 9.652)
			(stroke
				(width 0.1524)
				(type default)
			)
			(layer "F.SilkS")
		)
		(fp_line
			(start 17.8435 9.652)
			(end 17.8435 7.9502)
			(stroke
				(width 0.1524)
				(type default)
			)
			(layer "F.SilkS")
		)
		(fp_line
			(start -17.8435 9.652)
			(end -20.4724 9.652)
			(stroke
				(width 0.1524)
				(type default)
			)
			(layer "F.SilkS")
		)
		(fp_line
			(start -20.4724 9.652)
			(end -20.4724 2.3114)
			(stroke
				(width 0.1524)
				(type default)
			)
			(layer "F.SilkS")
		)
		(fp_arc
			(start 20.882356 -0.5461)
			(mid 21.999956 -1.6637)
			(end 23.117556 -0.5461)
			(stroke
				(width 0.3048)
				(type default)
			)
			(layer "F.SilkS")
		)
		(fp_arc
			(start -23.117556 -0.5461)
			(mid -21.999956 -1.6637)
			(end -20.882356 -0.5461)
			(stroke
				(width 0.3048)
				(type default)
			)
			(layer "F.SilkS")
		)
		(fp_arc
			(start 23.117556 0.5461)
			(mid 21.999956 1.6637)
			(end 20.882356 0.5461)
			(stroke
				(width 0.3048)
				(type default)
			)
			(layer "F.SilkS")
		)
		(fp_arc
			(start -20.882356 0.5461)
			(mid -21.999956 1.6637)
			(end -23.117556 0.5461)
			(stroke
				(width 0.3048)
				(type default)
			)
			(layer "F.SilkS")
		)
		(fp_poly
			(pts
				(xy -15.87119 -5.838698) (xy -15.23619 -6.473698) (xy -16.50619 -6.473698)
			)
			(stroke
				(width 0)
				(type default)
			)
			(fill yes)
			(layer "F.SilkS")
		)
		(fp_poly
			(pts
				(xy -20.2184 -5.5118) (xy 20.2184 -5.5118) (xy 20.2184 -2.0574) (xy 23.5077 -2.0574) (xy 23.5077 2.0574)
				(xy 20.2184 2.0574) (xy 20.2184 9.398) (xy 18.0975 9.398) (xy 18.0975 7.6962) (xy -18.0975 7.6962)
				(xy -18.0975 9.398) (xy -20.2184 9.398) (xy -20.2184 2.0574) (xy -23.5077 2.0574) (xy -23.5077 -2.0574)
				(xy -20.2184 -2.0574)
			)
			(stroke
				(width 0)
				(type default)
			)
			(fill no)
			(layer "F.CrtYd")
		)
		(fp_poly
			(pts
				(xy -20.2184 -5.5118) (xy -20.2184 -6.0198) (xy -20.7264 -6.0198) (xy -20.7264 -2.5654) (xy -24.0157 -2.5654)
				(xy -24.0157 2.5654) (xy -20.7264 2.5654) (xy -20.7264 9.906) (xy -17.5895 9.906) (xy -17.5895 8.2042)
				(xy 17.5895 8.2042) (xy 17.5895 9.906) (xy 20.7264 9.906) (xy 20.7264 2.5654) (xy 24.0157 2.5654)
				(xy 24.0157 -2.5654) (xy 20.7264 -2.5654) (xy 20.7264 -6.0198) (xy -20.21586 -6.0198) (xy -20.21586 -5.5118)
				(xy 20.2184 -5.5118) (xy 20.2184 -2.0574) (xy 23.5077 -2.0574) (xy 23.5077 2.0574) (xy 20.2184 2.0574)
				(xy 20.2184 9.398) (xy 18.0975 9.398) (xy 18.0975 7.6962) (xy -18.0975 7.6962) (xy -18.0975 9.398)
				(xy -20.2184 9.398) (xy -20.2184 2.0574) (xy -23.5077 2.0574) (xy -23.5077 -2.0574) (xy -20.2184 -2.0574)
			)
			(stroke
				(width 0)
				(type default)
			)
			(fill no)
			(layer "F.CrtYd")
		)
		(fp_poly
			(pts
				(xy -20.7264 -6.0198) (xy -20.7264 -2.5654) (xy -24.0157 -2.5654) (xy -24.0157 2.5654) (xy -20.7264 2.5654)
				(xy -20.7264 9.906) (xy -17.5895 9.906) (xy -17.5895 8.2042) (xy 17.5895 8.2042) (xy 17.5895 9.906)
				(xy 20.7264 9.906) (xy 20.7264 2.5654) (xy 24.0157 2.5654) (xy 24.0157 -2.5654) (xy 20.7264 -2.5654)
				(xy 20.7264 -6.0198)
			)
			(stroke
				(width 0)
				(type default)
			)
			(fill no)
			(layer "F.Fab")
		)
		(pad "" np_thru_hole circle
			(at -18.999962 -2.350008 90)
			(size 0.254 0.254)
			(drill 1.8542)
			(layers "*.Cu" "*.Mask")
			(clearance 1.1557)
			(thermal_gap 1.1557)
		)
		(pad "" np_thru_hole circle
			(at 18.999962 -2.350008 90)
			(size 0.254 0.254)
			(drill 1.8542)
			(layers "*.Cu" "*.Mask")
			(clearance 1.1557)
			(thermal_gap 1.1557)
		)
		(pad "H1" thru_hole oval
			(at -21.999956 0 90)
			(size 1.524 2.6162)
			(drill oval 0.8128 1.905)
			(layers "*.Cu" "*.Mask")
			(remove_unused_layers no)
			(net "GND")
			(clearance 0.1524)
			(thermal_gap 0.1524)
		)
		(pad "H2" thru_hole oval
			(at 21.999956 0 90)
			(size 1.524 2.6162)
			(drill oval 0.8128 1.905)
			(layers "*.Cu" "*.Mask")
			(remove_unused_layers no)
			(net "GND")
			(clearance 0.1524)
			(thermal_gap 0.1524)
		)
		(pad "P1" smd rect
			(at -1.89992 -4.249928 90)
			(size 0.6604 2.3876)
			(layers "F.Cu" "F.Mask" "F.Paste")
			(net "Net_70")
		)
		(pad "P2" smd rect
			(at -0.62992 -4.249928 90)
			(size 0.6604 2.3876)
			(layers "F.Cu" "F.Mask" "F.Paste")
			(net "Net_69")
		)
		(pad "P3" smd rect
			(at 0.64008 -4.249928 90)
			(size 0.6604 2.3876)
			(layers "F.Cu" "F.Mask" "F.Paste")
			(net "Net_68")
		)
		(pad "P4" smd rect
			(at 1.91008 -4.249928 90)
			(size 0.6604 2.3876)
			(layers "F.Cu" "F.Mask" "F.Paste")
			(net "GND")
		)
		(pad "P5" smd rect
			(at 3.18008 -4.249928 90)
			(size 0.6604 2.3876)
			(layers "F.Cu" "F.Mask" "F.Paste")
			(net "HDD_PRSNT_NET9")
		)
		(pad "P6" smd rect
			(at 4.45008 -4.249928 90)
			(size 0.6604 2.3876)
			(layers "F.Cu" "F.Mask" "F.Paste")
			(net "GND")
		)
		(pad "P7" smd rect
			(at 5.72008 -4.249928 90)
			(size 0.6604 2.3876)
			(layers "F.Cu" "F.Mask" "F.Paste")
			(net "5V_PRE_9")
		)
		(pad "P8" smd rect
			(at 6.99008 -4.249928 90)
			(size 0.6604 2.3876)
			(layers "F.Cu" "F.Mask" "F.Paste")
			(net "P5V_HDD9")
		)
		(pad "P9" smd rect
			(at 8.26008 -4.249928 90)
			(size 0.6604 2.3876)
			(layers "F.Cu" "F.Mask" "F.Paste")
			(net "P5V_HDD9")
		)
		(pad "P10" smd rect
			(at 9.53008 -4.249928 90)
			(size 0.6604 2.3876)
			(layers "F.Cu" "F.Mask" "F.Paste")
			(net "GND")
		)
		(pad "P11" smd rect
			(at 10.80008 -4.249928 90)
			(size 0.6604 2.3876)
			(layers "F.Cu" "F.Mask" "F.Paste")
			(net "ACT_HDD9")
		)
		(pad "P12" smd rect
			(at 12.07008 -4.249928 90)
			(size 0.6604 2.3876)
			(layers "F.Cu" "F.Mask" "F.Paste")
			(net "GND")
		)
		(pad "P13" smd rect
			(at 13.34008 -4.249928 90)
			(size 0.6604 2.3876)
			(layers "F.Cu" "F.Mask" "F.Paste")
			(net "12V_PRE_9")
		)
		(pad "P14" smd rect
			(at 14.61008 -4.249928 90)
			(size 0.6604 2.3876)
			(layers "F.Cu" "F.Mask" "F.Paste")
			(net "P12V_HDD9")
		)
		(pad "P15" smd rect
			(at 15.88008 -4.249928 90)
			(size 0.6604 2.3876)
			(layers "F.Cu" "F.Mask" "F.Paste")
			(net "P12V_HDD9")
		)
		(pad "S1" smd rect
			(at -15.86992 -4.249928 90)
			(size 0.6604 2.3876)
			(layers "F.Cu" "F.Mask" "F.Paste")
			(net "GND")
		)
		(pad "S2" smd rect
			(at -14.59992 -4.249928 90)
			(size 0.6604 2.3876)
			(layers "F.Cu" "F.Mask" "F.Paste")
			(net "SAS2X28_A_HDD9_TX_+")
		)
		(pad "S3" smd rect
			(at -13.32992 -4.249928 90)
			(size 0.6604 2.3876)
			(layers "F.Cu" "F.Mask" "F.Paste")
			(net "SAS2X28_A_HDD9_TX_-")
		)
		(pad "S4" smd rect
			(at -12.05992 -4.249928 90)
			(size 0.6604 2.3876)
			(layers "F.Cu" "F.Mask" "F.Paste")
			(net "GND")
		)
		(pad "S5" smd rect
			(at -10.78992 -4.249928 90)
			(size 0.6604 2.3876)
			(layers "F.Cu" "F.Mask" "F.Paste")
			(net "SAS2X28_DRIVE_RX_N_A9")
		)
		(pad "S6" smd rect
			(at -9.51992 -4.249928 90)
			(size 0.6604 2.3876)
			(layers "F.Cu" "F.Mask" "F.Paste")
			(net "SAS2X28_DRIVE_RX_P_A9")
		)
		(pad "S7" smd rect
			(at -8.24992 -4.249928 90)
			(size 0.6604 2.3876)
			(layers "F.Cu" "F.Mask" "F.Paste")
			(net "GND")
		)
		(pad "S8" smd rect
			(at -7.480046 -2.100072 90)
			(size 0.508 1.905)
			(layers "F.Cu" "F.Mask" "F.Paste")
			(net "GND")
		)
		(pad "S9" smd rect
			(at -6.679946 -2.100072 90)
			(size 0.508 1.905)
			(layers "F.Cu" "F.Mask" "F.Paste")
			(net "SAS2X28_B_HDD9_TX_+")
		)
		(pad "S10" smd rect
			(at -5.8801 -2.100072 90)
			(size 0.508 1.905)
			(layers "F.Cu" "F.Mask" "F.Paste")
			(net "SAS2X28_B_HDD9_TX_-")
		)
		(pad "S11" smd rect
			(at -5.08 -2.100072 90)
			(size 0.508 1.905)
			(layers "F.Cu" "F.Mask" "F.Paste")
			(net "GND")
		)
		(pad "S12" smd rect
			(at -4.2799 -2.100072 90)
			(size 0.508 1.905)
			(layers "F.Cu" "F.Mask" "F.Paste")
			(net "SAS2X28_DRIVE_RX_N_B9")
		)
		(pad "S13" smd rect
			(at -3.480054 -2.100072 90)
			(size 0.508 1.905)
			(layers "F.Cu" "F.Mask" "F.Paste")
			(net "SAS2X28_DRIVE_RX_P_B9")
		)
		(pad "S14" smd rect
			(at -2.679954 -2.100072 90)
			(size 0.508 1.905)
			(layers "F.Cu" "F.Mask" "F.Paste")
			(net "GND")
		)
		(zone
			(layers "F.Cu" "B.Cu" "In1.Cu" "In2.Cu" "In3.Cu" "In4.Cu" "In5.Cu" "In6.Cu")
			(hatch none 0.5)
			(connect_pads
				(clearance 0)
			)
			(min_thickness 0.25)
			(keepout
				(tracks not_allowed)
				(vias allowed)
				(pads allowed)
				(copperpour not_allowed)
				(footprints allowed)
			)
			(placement
				(enabled no)
				(sheetname "")
			)
			(fill
				(thermal_gap 0.5)
				(thermal_bridge_width 0.5)
				(island_removal_mode 0)
			)
			(polygon
				(pts
					(arc
						(start 41.381934 -86.66988)
						(mid 38.918134 -86.66988)
						(end 41.381934 -86.66988)
					)
				)
			)
		)
		(zone
			(layers "F.Cu" "B.Cu" "In1.Cu" "In2.Cu" "In3.Cu" "In4.Cu" "In5.Cu" "In6.Cu")
			(hatch none 0.5)
			(connect_pads
				(clearance 0)
			)
			(min_thickness 0.25)
			(keepout
				(tracks not_allowed)
				(vias allowed)
				(pads allowed)
				(copperpour not_allowed)
				(footprints allowed)
			)
			(placement
				(enabled no)
				(sheetname "")
			)
			(fill
				(thermal_gap 0.5)
				(thermal_bridge_width 0.5)
				(island_removal_mode 0)
			)
			(polygon
				(pts
					(arc
						(start 41.381934 -48.669956)
						(mid 38.918134 -48.669956)
						(end 41.381934 -48.669956)
					)
				)
			)
		)
	)
	(footprint ""
		(layer "F.Cu")
		(at 74.675746 -15.014702)
		(property "Reference" "C330"
			(at 0 0 0)
			(layer "F.SilkS")
			(hide yes)
			(effects
				(font
					(size 1.27 1.27)
				)
			)
		)
		(property "Value" "SC1U16V3KX-5GP"
			(at 0 -2.8194 0)
			(unlocked yes)
			(layer "F.Fab")
			(hide yes)
			(effects
				(font
					(size 1.016 1.016)
					(thickness 0.1524)
				)
			)
		)
		(property "Device Type" "C603H36"
			(at 0 -4.3434 0)
			(unlocked yes)
			(layer "F.Fab")
			(hide yes)
			(effects
				(font
					(size 1.016 1.016)
					(thickness 0.1524)
				)
			)
		)
		(duplicate_pad_numbers_are_jumpers no)
		(fp_line
			(start 0.508 0)
			(end -0.508 0)
			(stroke
				(width 0.2032)
				(type default)
			)
			(layer "F.SilkS")
		)
		(fp_rect
			(start -0.5842 1.3335)
			(end 0.5842 -1.3335)
			(stroke
				(width 0)
				(type default)
			)
			(fill no)
			(layer "F.CrtYd")
		)
		(fp_rect
			(start -0.5842 1.3335)
			(end 0.5842 -1.3335)
			(stroke
				(width 0)
				(type default)
			)
			(fill no)
			(layer "F.Fab")
		)
		(pad "1" smd custom
			(at 0 -0.762)
			(size 0.2159 0.2159)
			(layers "F.Cu" "F.Mask" "F.Paste")
			(net "P5V_HDD14")
			(options
				(clearance outline)
				(anchor circle)
			)
			(primitives
				(gr_poly
					(pts
						(arc
							(start -0.3302 -0.4318)
							(mid -0.402042 -0.402042)
							(end -0.4318 -0.3302)
						)
						(arc
							(start -0.4318 0.3302)
							(mid -0.402042 0.402042)
							(end -0.3302 0.4318)
						)
						(arc
							(start 0.3302 0.4318)
							(mid 0.402042 0.402042)
							(end 0.4318 0.3302)
						)
						(arc
							(start 0.4318 -0.3302)
							(mid 0.402042 -0.402042)
							(end 0.3302 -0.4318)
						)
					)
					(width 0)
					(fill yes)
				)
			)
		)
		(pad "2" smd custom
			(at 0 0.762)
			(size 0.2159 0.2159)
			(layers "F.Cu" "F.Mask" "F.Paste")
			(net "GND")
			(options
				(clearance outline)
				(anchor circle)
			)
			(primitives
				(gr_poly
					(pts
						(arc
							(start -0.3302 -0.4318)
							(mid -0.402042 -0.402042)
							(end -0.4318 -0.3302)
						)
						(arc
							(start -0.4318 0.3302)
							(mid -0.402042 0.402042)
							(end -0.3302 0.4318)
						)
						(arc
							(start 0.3302 0.4318)
							(mid 0.402042 0.402042)
							(end 0.4318 0.3302)
						)
						(arc
							(start 0.4318 -0.3302)
							(mid 0.402042 -0.402042)
							(end 0.3302 -0.4318)
						)
					)
					(width 0)
					(fill yes)
				)
			)
		)
	)
	(footprint ""
		(layer "F.Cu")
		(at 93.218 -11.303 180)
		(property "Reference" "C393"
			(at 0 0 180)
			(layer "F.SilkS")
			(hide yes)
			(effects
				(font
					(size 1.27 1.27)
				)
			)
		)
		(property "Value" "SCD033U25V2KX-GP"
			(at 1.1811 -2.7051 180)
			(unlocked yes)
			(layer "F.Fab")
			(hide yes)
			(effects
				(font
					(size 1.016 1.016)
					(thickness 0.1524)
				)
			)
		)
		(property "Device Type" "C402H22"
			(at 1.1811 -4.2291 180)
			(unlocked yes)
			(layer "F.Fab")
			(hide yes)
			(effects
				(font
					(size 1.016 1.016)
					(thickness 0.1524)
				)
			)
		)
		(duplicate_pad_numbers_are_jumpers no)
		(fp_rect
			(start -0.4318 0.9525)
			(end 0.4318 -0.9525)
			(stroke
				(width 0)
				(type default)
			)
			(fill no)
			(layer "F.CrtYd")
		)
		(fp_rect
			(start -0.4318 0.9525)
			(end 0.4318 -0.9525)
			(stroke
				(width 0)
				(type default)
			)
			(fill no)
			(layer "F.Fab")
		)
		(pad "1" smd custom
			(at 0 -0.4445 180)
			(size 0.1524 0.1524)
			(layers "F.Cu" "F.Mask" "F.Paste")
			(net "P12V")
			(options
				(clearance outline)
				(anchor circle)
			)
			(primitives
				(gr_poly
					(pts
						(arc
							(start 0.3048 -0.2032)
							(mid 0.275042 -0.275042)
							(end 0.2032 -0.3048)
						)
						(arc
							(start -0.2032 -0.3048)
							(mid -0.275042 -0.275042)
							(end -0.3048 -0.2032)
						)
						(arc
							(start -0.3048 0.2032)
							(mid -0.275042 0.275042)
							(end -0.2032 0.3048)
						)
						(arc
							(start 0.2032 0.3048)
							(mid 0.275042 0.275042)
							(end 0.3048 0.2032)
						)
					)
					(width 0)
					(fill yes)
				)
			)
		)
		(pad "2" smd custom
			(at 0 0.4445 180)
			(size 0.1524 0.1524)
			(layers "F.Cu" "F.Mask" "F.Paste")
			(net "SW_HDD14_N")
			(options
				(clearance outline)
				(anchor circle)
			)
			(primitives
				(gr_poly
					(pts
						(arc
							(start 0.3048 -0.2032)
							(mid 0.275042 -0.275042)
							(end 0.2032 -0.3048)
						)
						(arc
							(start -0.2032 -0.3048)
							(mid -0.275042 -0.275042)
							(end -0.3048 -0.2032)
						)
						(arc
							(start -0.3048 0.2032)
							(mid -0.275042 0.275042)
							(end -0.2032 0.3048)
						)
						(arc
							(start 0.2032 0.3048)
							(mid 0.275042 0.275042)
							(end 0.3048 0.2032)
						)
					)
					(width 0)
					(fill yes)
				)
			)
		)
	)
)
